#ISCELL
  logical_power bom_note *
  *
#ISCELL
  logical_power cad_note *
  *
#ISCELL
  pure_quanta quanta_title_block_c *
  *
#ISCELL
  standard tap *
  page82_i10
#ISCELL
  standard offpage *
  page82_i100
#ISCELL
  standard offpage *
  page82_i101
#ISCELL
  standard offpage *
  page82_i102
#ISCELL
  standard offpage *
  page82_i103
#ISCELL
  standard tap *
  page82_i104
#ISCELL
  standard tap *
  page82_i105
#ISCELL
  standard tap *
  page82_i106
#ISCELL
  standard tap *
  page82_i107
#ISCELL
  standard tap *
  page82_i108
#ISCELL
  standard tap *
  page82_i109
#ISCELL
  standard tap *
  page82_i11
#ISCELL
  standard tap *
  page82_i110
#ISCELL
  standard tap *
  page82_i111
#ISCELL
  standard tap *
  page82_i112
#ISCELL
  standard tap *
  page82_i113
#ISCELL
  standard tap *
  page82_i114
#ISCELL
  standard tap *
  page82_i115
#ISCELL
  standard tap *
  page82_i116
#ISCELL
  standard tap *
  page82_i117
#ISCELL
  standard tap *
  page82_i118
#ISCELL
  standard tap *
  page82_i119
#ISCELL
  standard tap *
  page82_i12
#ISCELL
  standard tap *
  page82_i120
#ISCELL
  standard tap *
  page82_i121
#ISCELL
  standard tap *
  page82_i122
#ISCELL
  standard tap *
  page82_i123
#ISCELL
  standard tap *
  page82_i124
#ISCELL
  standard tap *
  page82_i125
#ISCELL
  standard tap *
  page82_i126
#ISCELL
  standard tap *
  page82_i128
#ISCELL
  standard tap *
  page82_i129
#ISCELL
  standard tap *
  page82_i13
#ISCELL
  standard tap *
  page82_i130
#ISCELL
  standard tap *
  page82_i131
#ISCELL
  standard offpage *
  page82_i132
#ISCELL
  standard tap *
  page82_i133
#ISCELL
  standard tap *
  page82_i134
#ISCELL
  standard tap *
  page82_i135
#ISCELL
  standard tap *
  page82_i136
#ISCELL
  standard tap *
  page82_i137
#ISCELL
  standard tap *
  page82_i138
#ISCELL
  standard offpage *
  page82_i139
#ISCELL
  standard offpage *
  page82_i14
#ISCELL
  standard tap *
  page82_i140
#ISCELL
  standard offpage *
  page82_i142
#ISCELL
  standard offpage *
  page82_i143
#ISCELL
  standard offpage *
  page82_i144
#ISCELL
  standard offpage *
  page82_i145
#ISCELL
  standard offpage *
  page82_i146
#ISCELL
  standard offpage *
  page82_i147
#ISCELL
  standard offpage *
  page82_i148
#ISCELL
  standard offpage *
  page82_i149
#ISCELL
  standard tap *
  page82_i15
#ISCELL
  standard tap *
  page82_i157
#ISCELL
  standard tap *
  page82_i158
#ISCELL
  standard tap *
  page82_i16
#ISCELL
  standard tap *
  page82_i160
#ISCELL
  standard tap *
  page82_i161
#ISCELL
  standard tap *
  page82_i162
#ISCELL
  standard tap *
  page82_i163
#ISCELL
  standard tap *
  page82_i164
#ISCELL
  standard tap *
  page82_i165
#ISCELL
  standard offpage *
  page82_i166
#ISCELL
  standard tap *
  page82_i167
#ISCELL
  standard tap *
  page82_i168
#ISCELL
  standard tap *
  page82_i169
#ISCELL
  standard tap *
  page82_i17
#ISCELL
  standard tap *
  page82_i170
#ISCELL
  standard tap *
  page82_i171
#ISCELL
  standard tap *
  page82_i172
#ISCELL
  standard tap *
  page82_i173
#ISCELL
  standard tap *
  page82_i174
#ISCELL
  standard offpage *
  page82_i175
#ISCELL
  standard offpage *
  page82_i176
#ISCELL
  standard offpage *
  page82_i177
#ISCELL
  standard offpage *
  page82_i178
#ISCELL
  standard tap *
  page82_i18
#ISCELL
  standard offpage *
  page82_i180
#ISCELL
  standard offpage *
  page82_i181
#ISCELL
  standard offpage *
  page82_i182
#ISCELL
  logical_power vcc_core *
  page82_i183
#ISCELL
  logical_power universal_gnd *
  page82_i184
#ISCELL
  logical_power universal_gnd *
  page82_i185
#ISCELL
  logical_power vcc_core *
  page82_i186
#ISCELL
  logical_power vcc_core *
  page82_i187
#CELL
  pure_quanta q_cap *
  page82_i188
#ISCELL
  standard tap *
  page82_i19
#CELL
  pure_quanta q_cap *
  page82_i190
#ISCELL
  logical_power universal_gnd *
  page82_i191
#CELL
  pure_quanta q_cap *
  page82_i192
#ISCELL
  logical_power vcc_core *
  page82_i193
#ISCELL
  logical_power universal_gnd *
  page82_i194
#ISCELL
  standard offpage *
  page82_i195
#CELL
  pure_quanta q_res *
  page82_i196
#ISCELL
  logical_power universal_gnd *
  page82_i197
#CELL
  pure_quanta sconn288_adr50017p130cc *
  page82_i198
#ISCELL
  standard tap *
  page82_i20
#ISCELL
  standard offpage *
  page82_i201
#CELL
  pure_quanta sconn288_adr50017p130cc *
  page82_i202
#CELL
  pure_quanta sconn288_adr50017p130cc *
  page82_i203
#CELL
  pure_quanta q_res *
  page82_i204
#ISCELL
  standard offpage *
  page82_i205
#ISCELL
  standard tap *
  page82_i21
#ISCELL
  standard tap *
  page82_i22
#ISCELL
  standard tap *
  page82_i23
#ISCELL
  standard tap *
  page82_i24
#ISCELL
  standard tap *
  page82_i25
#ISCELL
  standard tap *
  page82_i26
#ISCELL
  standard tap *
  page82_i27
#ISCELL
  standard tap *
  page82_i28
#ISCELL
  standard tap *
  page82_i29
#ISCELL
  standard tap *
  page82_i30
#ISCELL
  standard tap *
  page82_i31
#ISCELL
  standard tap *
  page82_i32
#ISCELL
  standard tap *
  page82_i33
#ISCELL
  standard tap *
  page82_i34
#ISCELL
  standard tap *
  page82_i35
#ISCELL
  standard tap *
  page82_i36
#ISCELL
  standard tap *
  page82_i37
#ISCELL
  standard tap *
  page82_i38
#ISCELL
  standard tap *
  page82_i39
#ISCELL
  standard tap *
  page82_i4
#ISCELL
  standard tap *
  page82_i40
#ISCELL
  standard tap *
  page82_i41
#ISCELL
  standard tap *
  page82_i42
#ISCELL
  standard tap *
  page82_i43
#ISCELL
  standard tap *
  page82_i44
#ISCELL
  standard tap *
  page82_i45
#ISCELL
  standard tap *
  page82_i46
#ISCELL
  standard tap *
  page82_i47
#ISCELL
  standard tap *
  page82_i48
#ISCELL
  standard tap *
  page82_i49
#ISCELL
  standard tap *
  page82_i5
#ISCELL
  standard tap *
  page82_i50
#ISCELL
  standard tap *
  page82_i51
#ISCELL
  standard tap *
  page82_i52
#ISCELL
  standard tap *
  page82_i53
#ISCELL
  standard tap *
  page82_i54
#ISCELL
  standard tap *
  page82_i55
#ISCELL
  standard tap *
  page82_i56
#ISCELL
  standard tap *
  page82_i57
#ISCELL
  standard tap *
  page82_i58
#ISCELL
  standard tap *
  page82_i59
#ISCELL
  standard tap *
  page82_i6
#ISCELL
  standard tap *
  page82_i60
#ISCELL
  standard tap *
  page82_i61
#ISCELL
  standard tap *
  page82_i62
#ISCELL
  standard tap *
  page82_i63
#ISCELL
  standard tap *
  page82_i64
#ISCELL
  standard tap *
  page82_i65
#ISCELL
  standard tap *
  page82_i66
#ISCELL
  standard tap *
  page82_i67
#ISCELL
  standard offpage *
  page82_i68
#ISCELL
  standard tap *
  page82_i69
#ISCELL
  standard tap *
  page82_i7
#ISCELL
  standard tap *
  page82_i72
#ISCELL
  standard tap *
  page82_i74
#ISCELL
  standard tap *
  page82_i75
#ISCELL
  standard tap *
  page82_i78
#ISCELL
  standard tap *
  page82_i8
#ISCELL
  standard tap *
  page82_i80
#ISCELL
  standard tap *
  page82_i82
#ISCELL
  standard tap *
  page82_i84
#ISCELL
  standard tap *
  page82_i87
#ISCELL
  standard tap *
  page82_i88
#ISCELL
  standard tap *
  page82_i89
#ISCELL
  standard tap *
  page82_i9
#ISCELL
  standard tap *
  page82_i90
#ISCELL
  standard tap *
  page82_i91
#ISCELL
  standard tap *
  page82_i92
#ISCELL
  standard tap *
  page82_i93
#ISCELL
  standard tap *
  page82_i94
#ISCELL
  standard tap *
  page82_i95
#ISCELL
  standard tap *
  page82_i96
#ISCELL
  standard tap *
  page82_i97
#ISCELL
  standard tap *
  page82_i98
#ISCELL
  standard tap *
  page82_i99
